(kicad_pcb
	(version 20260206)
	(generator "pcbnew")
	(generator_version "10.0")
	(general
		(thickness 1.6)
		(legacy_teardrops no)
	)
	(paper "A4")
	(title_block
		(title "Bryce Canyon_R.DPB_16317-1_OCP.brd")
		(comment 1 "Bryce Canyon / footprints 1562-1569 of 2099")
	)
	(layers
		(0 "F.Cu" signal "TOP")
		(4 "In1.Cu" signal "L2GND")
		(6 "In2.Cu" signal "L3")
		(8 "In3.Cu" signal "L4VCC")
		(10 "In4.Cu" signal "L5VCC")
		(12 "In5.Cu" signal "L6")
		(14 "In6.Cu" signal "L7GND")
		(2 "B.Cu" signal "BOTTOM")
		(9 "F.Adhes" user "F.Adhesive")
		(11 "B.Adhes" user "B.Adhesive")
		(13 "F.Paste" user "Package Geometry/Pastemask Top")
		(15 "B.Paste" user "Package Geometry/Pastemask Bottom")
		(5 "F.SilkS" user "Ref Des/Silkscreen Top")
		(7 "B.SilkS" user "Ref Des/Silkscreen Bottom")
		(1 "F.Mask" user "Board Geometry/Soldermask Top")
		(3 "B.Mask" user "Board Geometry/Soldermask Bottom")
		(17 "Dwgs.User" user "User.Drawings")
		(19 "Cmts.User" user "User.Comments")
		(21 "Eco1.User" user "User.Eco1")
		(23 "Eco2.User" user "User.Eco2")
		(25 "Edge.Cuts" user "Board Geometry/Outline")
		(27 "Margin" user)
		(31 "F.CrtYd" user "Package Geometry/Place Bound Top")
		(29 "B.CrtYd" user "Package Geometry/Place Bound Bottom")
		(35 "F.Fab" user "Ref Des/Assembly Top")
		(33 "B.Fab" user "Ref Des/Assembly Bottom")
	)
	(footprint ""
		(layer "F.Cu")
		(at 409.194 -214.249)
		(property "Reference" "R348"
			(at 0 0 0)
			(layer "F.SilkS")
			(hide yes)
			(effects
				(font
					(size 1.27 1.27)
				)
			)
		)
		(property "Value" "130R3F-GP"
			(at -0.0254 -2.5146 0)
			(unlocked yes)
			(layer "F.Fab")
			(hide yes)
			(effects
				(font
					(size 1.016 1.016)
					(thickness 0.1524)
				)
			)
		)
		(property "Device Type" "R603H22"
			(at -0.0254 -4.0386 0)
			(unlocked yes)
			(layer "F.Fab")
			(hide yes)
			(effects
				(font
					(size 1.016 1.016)
					(thickness 0.1524)
				)
			)
		)
		(duplicate_pad_numbers_are_jumpers no)
		(fp_line
			(start -0.4826 0)
			(end -0.2032 0)
			(stroke
				(width 0.2032)
				(type default)
			)
			(layer "F.SilkS")
		)
		(fp_line
			(start 0.2032 0)
			(end 0.4826 0)
			(stroke
				(width 0.2032)
				(type default)
			)
			(layer "F.SilkS")
		)
		(fp_rect
			(start -0.5842 1.3335)
			(end 0.5842 -1.3335)
			(stroke
				(width 0)
				(type default)
			)
			(fill no)
			(layer "F.CrtYd")
		)
		(fp_rect
			(start -0.5842 1.3335)
			(end 0.5842 -1.3335)
			(stroke
				(width 0)
				(type default)
			)
			(fill no)
			(layer "F.Fab")
		)
		(pad "1" smd custom
			(at 0 -0.762)
			(size 0.2159 0.2159)
			(layers "F.Cu" "F.Mask" "F.Paste")
			(net "P5V_B_3")
			(options
				(clearance outline)
				(anchor circle)
			)
			(primitives
				(gr_poly
					(pts
						(arc
							(start -0.3302 -0.4318)
							(mid -0.402042 -0.402042)
							(end -0.4318 -0.3302)
						)
						(arc
							(start -0.4318 0.3302)
							(mid -0.402042 0.402042)
							(end -0.3302 0.4318)
						)
						(arc
							(start 0.3302 0.4318)
							(mid 0.402042 0.402042)
							(end 0.4318 0.3302)
						)
						(arc
							(start 0.4318 -0.3302)
							(mid 0.402042 -0.402042)
							(end 0.3302 -0.4318)
						)
					)
					(width 0)
					(fill yes)
				)
			)
		)
		(pad "2" smd custom
			(at 0 0.762)
			(size 0.2159 0.2159)
			(layers "F.Cu" "F.Mask" "F.Paste")
			(net "FLT_HDD9")
			(options
				(clearance outline)
				(anchor circle)
			)
			(primitives
				(gr_poly
					(pts
						(arc
							(start -0.3302 -0.4318)
							(mid -0.402042 -0.402042)
							(end -0.4318 -0.3302)
						)
						(arc
							(start -0.4318 0.3302)
							(mid -0.402042 0.402042)
							(end -0.3302 0.4318)
						)
						(arc
							(start 0.3302 0.4318)
							(mid 0.402042 0.402042)
							(end 0.4318 0.3302)
						)
						(arc
							(start 0.4318 -0.3302)
							(mid 0.402042 -0.402042)
							(end 0.3302 -0.4318)
						)
					)
					(width 0)
					(fill yes)
				)
			)
		)
	)
	(footprint ""
		(layer "F.Cu")
		(at 192.035684 -129.99085 90)
		(property "Reference" "VIA35"
			(at 0 0 90)
			(layer "F.SilkS")
			(hide yes)
			(effects
				(font
					(size 1.27 1.27)
				)
			)
		)
		(property "Value" "100OHM-8L-2D36MM-L18-GP"
			(at 3.8989 0.5715 90)
			(unlocked yes)
			(layer "F.Fab")
			(hide yes)
			(effects
				(font
					(size 1.016 1.016)
					(thickness 0.1524)
				)
			)
		)
		(property "Device Type" "VIA-PCIE-4P-414097"
			(at 3.8989 -0.9525 90)
			(unlocked yes)
			(layer "F.Fab")
			(hide yes)
			(effects
				(font
					(size 1.016 1.016)
					(thickness 0.1524)
				)
			)
		)
		(duplicate_pad_numbers_are_jumpers no)
		(fp_rect
			(start -2.0701 0.4826)
			(end 2.0701 -0.4826)
			(stroke
				(width 0)
				(type default)
			)
			(fill no)
			(layer "F.CrtYd")
		)
		(fp_rect
			(start -2.0701 0.4826)
			(end 2.0701 -0.4826)
			(stroke
				(width 0)
				(type default)
			)
			(fill no)
			(layer "F.Fab")
		)
		(pad "1" thru_hole circle
			(at -1.5875 0 90)
			(size 0.508 0.508)
			(drill 0.254)
			(layers "*.Cu" "*.Mask")
			(remove_unused_layers no)
			(net "GND")
			(clearance 0.2286)
			(thermal_gap 0.2286)
		)
		(pad "2" thru_hole circle
			(at -0.5715 0 90)
			(size 0.508 0.508)
			(drill 0.254)
			(layers "*.Cu" "*.Mask")
			(remove_unused_layers no)
			(net "PHY_SCC_B_TO_DRV_B_17_DP")
			(clearance 0.2286)
			(thermal_gap 0.2286)
		)
		(pad "3" thru_hole circle
			(at 0.5715 0 90)
			(size 0.508 0.508)
			(drill 0.254)
			(layers "*.Cu" "*.Mask")
			(remove_unused_layers no)
			(net "PHY_SCC_B_TO_DRV_B_17_DN")
			(clearance 0.2286)
			(thermal_gap 0.2286)
		)
		(pad "4" thru_hole circle
			(at 1.5875 0 90)
			(size 0.508 0.508)
			(drill 0.254)
			(layers "*.Cu" "*.Mask")
			(remove_unused_layers no)
			(net "GND")
			(clearance 0.2286)
			(thermal_gap 0.2286)
		)
	)
	(footprint ""
		(layer "F.Cu")
		(at 171.831 -362.331)
		(property "Reference" "C547"
			(at 0 0 0)
			(layer "F.SilkS")
			(hide yes)
			(effects
				(font
					(size 1.27 1.27)
				)
			)
		)
		(property "Value" "SC1U16V3KX-5GP"
			(at 0 -2.8194 0)
			(unlocked yes)
			(layer "F.Fab")
			(hide yes)
			(effects
				(font
					(size 1.016 1.016)
					(thickness 0.1524)
				)
			)
		)
		(property "Device Type" "C603H36"
			(at 0 -4.3434 0)
			(unlocked yes)
			(layer "F.Fab")
			(hide yes)
			(effects
				(font
					(size 1.016 1.016)
					(thickness 0.1524)
				)
			)
		)
		(duplicate_pad_numbers_are_jumpers no)
		(fp_line
			(start 0.508 0)
			(end -0.508 0)
			(stroke
				(width 0.2032)
				(type default)
			)
			(layer "F.SilkS")
		)
		(fp_rect
			(start -0.5842 1.3335)
			(end 0.5842 -1.3335)
			(stroke
				(width 0)
				(type default)
			)
			(fill no)
			(layer "F.CrtYd")
		)
		(fp_rect
			(start -0.5842 1.3335)
			(end 0.5842 -1.3335)
			(stroke
				(width 0)
				(type default)
			)
			(fill no)
			(layer "F.Fab")
		)
		(pad "1" smd custom
			(at 0 -0.762)
			(size 0.2159 0.2159)
			(layers "F.Cu" "F.Mask" "F.Paste")
			(net "MB0_VCAP_R")
			(options
				(clearance outline)
				(anchor circle)
			)
			(primitives
				(gr_poly
					(pts
						(arc
							(start -0.3302 -0.4318)
							(mid -0.402042 -0.402042)
							(end -0.4318 -0.3302)
						)
						(arc
							(start -0.4318 0.3302)
							(mid -0.402042 0.402042)
							(end -0.3302 0.4318)
						)
						(arc
							(start 0.3302 0.4318)
							(mid 0.402042 0.402042)
							(end 0.4318 0.3302)
						)
						(arc
							(start 0.4318 -0.3302)
							(mid 0.402042 -0.402042)
							(end 0.3302 -0.4318)
						)
					)
					(width 0)
					(fill yes)
				)
			)
		)
		(pad "2" smd custom
			(at 0 0.762)
			(size 0.2159 0.2159)
			(layers "F.Cu" "F.Mask" "F.Paste")
			(net "AGND_CURRENT_MON")
			(options
				(clearance outline)
				(anchor circle)
			)
			(primitives
				(gr_poly
					(pts
						(arc
							(start -0.3302 -0.4318)
							(mid -0.402042 -0.402042)
							(end -0.4318 -0.3302)
						)
						(arc
							(start -0.4318 0.3302)
							(mid -0.402042 0.402042)
							(end -0.3302 0.4318)
						)
						(arc
							(start 0.3302 0.4318)
							(mid 0.402042 0.402042)
							(end 0.4318 0.3302)
						)
						(arc
							(start 0.4318 -0.3302)
							(mid 0.402042 -0.402042)
							(end 0.3302 -0.4318)
						)
					)
					(width 0)
					(fill yes)
				)
			)
		)
	)
	(footprint ""
		(layer "F.Cu")
		(at 242.062 -215.265 180)
		(property "Reference" "R85"
			(at 0 0 180)
			(layer "F.SilkS")
			(hide yes)
			(effects
				(font
					(size 1.27 1.27)
				)
			)
		)
		(property "Value" "4K7R2F-GP"
			(at 0.064008 -3.993896 180)
			(unlocked yes)
			(layer "F.Fab")
			(hide yes)
			(effects
				(font
					(size 1.016 1.016)
					(thickness 0.1524)
				)
			)
		)
		(property "Device Type" "R402H16"
			(at 0.064008 -5.517896 180)
			(unlocked yes)
			(layer "F.Fab")
			(hide yes)
			(effects
				(font
					(size 1.016 1.016)
					(thickness 0.1524)
				)
			)
		)
		(duplicate_pad_numbers_are_jumpers no)
		(fp_line
			(start 0.508 -0.9398)
			(end -0.508 -0.9398)
			(stroke
				(width 0.1524)
				(type default)
			)
			(layer "F.SilkS")
		)
		(fp_line
			(start -0.508 -0.9398)
			(end -0.508 0.9398)
			(stroke
				(width 0.1524)
				(type default)
			)
			(layer "F.SilkS")
		)
		(fp_rect
			(start -0.508 0.9398)
			(end 0.508 -0.9398)
			(stroke
				(width 0)
				(type default)
			)
			(fill no)
			(layer "F.CrtYd")
		)
		(fp_rect
			(start -0.508 0.9398)
			(end 0.508 -0.9398)
			(stroke
				(width 0)
				(type default)
			)
			(fill no)
			(layer "F.Fab")
		)
		(pad "1" smd custom
			(at 0 -0.4445 180)
			(size 0.1397 0.1397)
			(layers "F.Cu" "F.Mask" "F.Paste")
			(net "P3V3_STBY_B")
			(options
				(clearance outline)
				(anchor circle)
			)
			(primitives
				(gr_poly
					(pts
						(arc
							(start -0.1778 -0.2794)
							(mid -0.249642 -0.249642)
							(end -0.2794 -0.1778)
						)
						(arc
							(start -0.2794 0.1778)
							(mid -0.249642 0.249642)
							(end -0.1778 0.2794)
						)
						(arc
							(start 0.1778 0.2794)
							(mid 0.249642 0.249642)
							(end 0.2794 0.1778)
						)
						(arc
							(start 0.2794 -0.1778)
							(mid 0.249642 -0.249642)
							(end 0.1778 -0.2794)
						)
					)
					(width 0)
					(fill yes)
				)
			)
		)
		(pad "2" smd custom
			(at 0 0.4445 180)
			(size 0.1397 0.1397)
			(layers "F.Cu" "F.Mask" "F.Paste")
			(net "IO_EXP3_A1")
			(options
				(clearance outline)
				(anchor circle)
			)
			(primitives
				(gr_poly
					(pts
						(arc
							(start -0.1778 -0.2794)
							(mid -0.249642 -0.249642)
							(end -0.2794 -0.1778)
						)
						(arc
							(start -0.2794 0.1778)
							(mid -0.249642 0.249642)
							(end -0.1778 0.2794)
						)
						(arc
							(start 0.1778 0.2794)
							(mid 0.249642 0.249642)
							(end 0.2794 0.1778)
						)
						(arc
							(start 0.2794 -0.1778)
							(mid 0.249642 -0.249642)
							(end 0.1778 -0.2794)
						)
					)
					(width 0)
					(fill yes)
				)
			)
		)
	)
	(footprint ""
		(layer "F.Cu")
		(at 426.72 -16.256 -90)
		(property "Reference" "Q173"
			(at 0 0 270)
			(layer "F.SilkS")
			(hide yes)
			(effects
				(font
					(size 1.27 1.27)
				)
			)
		)
		(property "Value" "2N7002KDW-GP"
			(at -2.3622 -8.2042 270)
			(unlocked yes)
			(layer "F.Fab")
			(hide yes)
			(effects
				(font
					(size 1.016 1.016)
					(thickness 0.1524)
				)
			)
		)
		(property "Device Type" "SOT-363H44"
			(at -2.3622 -10.1092 270)
			(unlocked yes)
			(layer "F.Fab")
			(hide yes)
			(effects
				(font
					(size 1.016 1.016)
					(thickness 0.1524)
				)
			)
		)
		(duplicate_pad_numbers_are_jumpers no)
		(fp_line
			(start -1.4478 1.7018)
			(end 1.4478 1.7018)
			(stroke
				(width 0.1524)
				(type default)
			)
			(layer "F.SilkS")
		)
		(fp_line
			(start 1.4478 1.7018)
			(end 1.4478 -1.7018)
			(stroke
				(width 0.1524)
				(type default)
			)
			(layer "F.SilkS")
		)
		(fp_line
			(start -1.27 1.524)
			(end -1.27 0.6604)
			(stroke
				(width 0.4826)
				(type default)
			)
			(layer "F.SilkS")
		)
		(fp_line
			(start -1.4478 -1.7018)
			(end -1.4478 1.7018)
			(stroke
				(width 0.1524)
				(type default)
			)
			(layer "F.SilkS")
		)
		(fp_line
			(start 1.4478 -1.7018)
			(end -1.4478 -1.7018)
			(stroke
				(width 0.1524)
				(type default)
			)
			(layer "F.SilkS")
		)
		(fp_poly
			(pts
				(xy -1.524 -1.778) (xy 1.524 -1.778) (xy 1.524 1.778) (xy -1.524 1.778)
			)
			(stroke
				(width 0)
				(type default)
			)
			(fill no)
			(layer "F.CrtYd")
		)
		(fp_poly
			(pts
				(xy -1.524 -1.778) (xy 1.524 -1.778) (xy 1.524 1.778) (xy -1.524 1.778)
			)
			(stroke
				(width 0)
				(type default)
			)
			(fill no)
			(layer "F.Fab")
		)
		(pad "1" smd rect
			(at -0.65024 0.9398 270)
			(size 0.4064 1.016)
			(layers "F.Cu" "F.Mask" "F.Paste")
			(net "GND")
		)
		(pad "2" smd rect
			(at 0 0.9398 270)
			(size 0.4064 1.016)
			(layers "F.Cu" "F.Mask" "F.Paste")
			(net "SW_PWR_R_HDD33")
		)
		(pad "3" smd rect
			(at 0.65024 0.9398 270)
			(size 0.4064 1.016)
			(layers "F.Cu" "F.Mask" "F.Paste")
			(net "SW_HDD_P33")
		)
		(pad "4" smd rect
			(at 0.65024 -0.9398 270)
			(size 0.4064 1.016)
			(layers "F.Cu" "F.Mask" "F.Paste")
			(net "GND")
		)
		(pad "5" smd rect
			(at 0 -0.9398 270)
			(size 0.4064 1.016)
			(layers "F.Cu" "F.Mask" "F.Paste")
			(net "SW_HDD_G33")
		)
		(pad "6" smd rect
			(at -0.65024 -0.9398 270)
			(size 0.4064 1.016)
			(layers "F.Cu" "F.Mask" "F.Paste")
			(net "SW_HDD_R33")
		)
	)
	(footprint ""
		(layer "F.Cu")
		(at 16.764 -254.127 -90)
		(property "Reference" "C506"
			(at 0 0 270)
			(layer "F.SilkS")
			(hide yes)
			(effects
				(font
					(size 1.27 1.27)
				)
			)
		)
		(property "Value" "SCD033U25V2KX-GP"
			(at 1.1811 -2.7051 270)
			(unlocked yes)
			(layer "F.Fab")
			(hide yes)
			(effects
				(font
					(size 1.016 1.016)
					(thickness 0.1524)
				)
			)
		)
		(property "Device Type" "C402H22"
			(at 1.1811 -4.2291 270)
			(unlocked yes)
			(layer "F.Fab")
			(hide yes)
			(effects
				(font
					(size 1.016 1.016)
					(thickness 0.1524)
				)
			)
		)
		(duplicate_pad_numbers_are_jumpers no)
		(fp_rect
			(start -0.4318 0.9525)
			(end 0.4318 -0.9525)
			(stroke
				(width 0)
				(type default)
			)
			(fill no)
			(layer "F.CrtYd")
		)
		(fp_rect
			(start -0.4318 0.9525)
			(end 0.4318 -0.9525)
			(stroke
				(width 0)
				(type default)
			)
			(fill no)
			(layer "F.Fab")
		)
		(pad "1" smd custom
			(at 0 -0.4445 270)
			(size 0.1524 0.1524)
			(layers "F.Cu" "F.Mask" "F.Paste")
			(net "SW_HDD_P0")
			(options
				(clearance outline)
				(anchor circle)
			)
			(primitives
				(gr_poly
					(pts
						(arc
							(start 0.3048 -0.2032)
							(mid 0.275042 -0.275042)
							(end 0.2032 -0.3048)
						)
						(arc
							(start -0.2032 -0.3048)
							(mid -0.275042 -0.275042)
							(end -0.3048 -0.2032)
						)
						(arc
							(start -0.3048 0.2032)
							(mid -0.275042 0.275042)
							(end -0.2032 0.3048)
						)
						(arc
							(start 0.2032 0.3048)
							(mid 0.275042 0.275042)
							(end 0.3048 0.2032)
						)
					)
					(width 0)
					(fill yes)
				)
			)
		)
		(pad "2" smd custom
			(at 0 0.4445 270)
			(size 0.1524 0.1524)
			(layers "F.Cu" "F.Mask" "F.Paste")
			(net "GND")
			(options
				(clearance outline)
				(anchor circle)
			)
			(primitives
				(gr_poly
					(pts
						(arc
							(start 0.3048 -0.2032)
							(mid 0.275042 -0.275042)
							(end 0.2032 -0.3048)
						)
						(arc
							(start -0.2032 -0.3048)
							(mid -0.275042 -0.275042)
							(end -0.3048 -0.2032)
						)
						(arc
							(start -0.3048 0.2032)
							(mid -0.275042 0.275042)
							(end -0.2032 0.3048)
						)
						(arc
							(start 0.2032 0.3048)
							(mid 0.275042 0.275042)
							(end 0.3048 0.2032)
						)
					)
					(width 0)
					(fill yes)
				)
			)
		)
	)
	(footprint ""
		(layer "F.Cu")
		(at 186.7281 -379.5395 90)
		(property "Reference" "R970"
			(at 0 0 90)
			(layer "F.SilkS")
			(hide yes)
			(effects
				(font
					(size 1.27 1.27)
				)
			)
		)
		(property "Value" "270R5J-2-GP"
			(at 0 -8.9535 90)
			(unlocked yes)
			(layer "F.Fab")
			(hide yes)
			(effects
				(font
					(size 1.27 1.016)
					(thickness 0.1524)
				)
			)
		)
		(property "Device Type" "R805H24"
			(at 0 -10.6299 90)
			(unlocked yes)
			(layer "F.Fab")
			(hide yes)
			(effects
				(font
					(size 1.27 1.016)
					(thickness 0.1524)
				)
			)
		)
		(duplicate_pad_numbers_are_jumpers no)
		(fp_line
			(start 0.889 -1.7018)
			(end -0.889 -1.7018)
			(stroke
				(width 0.1524)
				(type default)
			)
			(layer "F.SilkS")
		)
		(fp_line
			(start 0.889 -1.7018)
			(end 0.889 -0.381)
			(stroke
				(width 0.1524)
				(type default)
			)
			(layer "F.SilkS")
		)
		(fp_line
			(start -0.889 -1.7018)
			(end -0.889 0.2794)
			(stroke
				(width 0.1524)
				(type default)
			)
			(layer "F.SilkS")
		)
		(fp_line
			(start -0.889 0.0762)
			(end -0.889 1.7018)
			(stroke
				(width 0.1524)
				(type default)
			)
			(layer "F.SilkS")
		)
		(fp_line
			(start 0.889 1.7018)
			(end 0.889 -0.508)
			(stroke
				(width 0.1524)
				(type default)
			)
			(layer "F.SilkS")
		)
		(fp_line
			(start -0.889 1.7018)
			(end 0.889 1.7018)
			(stroke
				(width 0.1524)
				(type default)
			)
			(layer "F.SilkS")
		)
		(fp_poly
			(pts
				(xy 0.9652 -1.778) (xy 0.9652 1.778) (xy -0.9652 1.778) (xy -0.9652 -1.778)
			)
			(stroke
				(width 0)
				(type default)
			)
			(fill no)
			(layer "F.CrtYd")
		)
		(fp_rect
			(start -0.9652 1.778)
			(end 0.9652 -1.778)
			(stroke
				(width 0)
				(type default)
			)
			(fill no)
			(layer "F.Fab")
		)
		(pad "1" smd rect
			(at 0 -0.9652 90)
			(size 1.397 1.143)
			(layers "F.Cu" "F.Mask" "F.Paste")
			(net "FAN_LED_BLUE1")
		)
		(pad "2" smd rect
			(at 0 0.9652 90)
			(size 1.397 1.143)
			(layers "F.Cu" "F.Mask" "F.Paste")
			(net "FAN_BLUE1")
		)
	)
	(footprint ""
		(layer "F.Cu")
		(at 470.281 -248.92 -90)
		(property "Reference" "R347"
			(at 0 0 270)
			(layer "F.SilkS")
			(hide yes)
			(effects
				(font
					(size 1.27 1.27)
				)
			)
		)
		(property "Value" "0R2J-2-GP"
			(at 0.064008 -3.993896 270)
			(unlocked yes)
			(layer "F.Fab")
			(hide yes)
			(effects
				(font
					(size 1.016 1.016)
					(thickness 0.1524)
				)
			)
		)
		(property "Device Type" "R402H16"
			(at 0.064008 -5.517896 270)
			(unlocked yes)
			(layer "F.Fab")
			(hide yes)
			(effects
				(font
					(size 1.016 1.016)
					(thickness 0.1524)
				)
			)
		)
		(duplicate_pad_numbers_are_jumpers no)
		(fp_line
			(start -0.508 -0.9398)
			(end -0.508 0.9398)
			(stroke
				(width 0.1524)
				(type default)
			)
			(layer "F.SilkS")
		)
		(fp_line
			(start 0.508 -0.9398)
			(end -0.508 -0.9398)
			(stroke
				(width 0.1524)
				(type default)
			)
			(layer "F.SilkS")
		)
		(fp_rect
			(start -0.508 0.9398)
			(end 0.508 -0.9398)
			(stroke
				(width 0)
				(type default)
			)
			(fill no)
			(layer "F.CrtYd")
		)
		(fp_rect
			(start -0.508 0.9398)
			(end 0.508 -0.9398)
			(stroke
				(width 0)
				(type default)
			)
			(fill no)
			(layer "F.Fab")
		)
		(pad "1" smd custom
			(at 0 -0.4445 270)
			(size 0.1397 0.1397)
			(layers "F.Cu" "F.Mask" "F.Paste")
			(net "SW_HDD_G11")
			(options
				(clearance outline)
				(anchor circle)
			)
			(primitives
				(gr_poly
					(pts
						(arc
							(start -0.1778 -0.2794)
							(mid -0.249642 -0.249642)
							(end -0.2794 -0.1778)
						)
						(arc
							(start -0.2794 0.1778)
							(mid -0.249642 0.249642)
							(end -0.1778 0.2794)
						)
						(arc
							(start 0.1778 0.2794)
							(mid 0.249642 0.249642)
							(end 0.2794 0.1778)
						)
						(arc
							(start 0.2794 -0.1778)
							(mid 0.249642 -0.249642)
							(end 0.1778 -0.2794)
						)
					)
					(width 0)
					(fill yes)
				)
			)
		)
		(pad "2" smd custom
			(at 0 0.4445 270)
			(size 0.1397 0.1397)
			(layers "F.Cu" "F.Mask" "F.Paste")
			(net "SW_HDD_R11")
			(options
				(clearance outline)
				(anchor circle)
			)
			(primitives
				(gr_poly
					(pts
						(arc
							(start -0.1778 -0.2794)
							(mid -0.249642 -0.249642)
							(end -0.2794 -0.1778)
						)
						(arc
							(start -0.2794 0.1778)
							(mid -0.249642 0.249642)
							(end -0.1778 0.2794)
						)
						(arc
							(start 0.1778 0.2794)
							(mid 0.249642 0.249642)
							(end 0.2794 0.1778)
						)
						(arc
							(start 0.2794 -0.1778)
							(mid 0.249642 -0.249642)
							(end 0.1778 -0.2794)
						)
					)
					(width 0)
					(fill yes)
				)
			)
		)
	)
)
